(kicad_pcb
	(version 20241229)
	(generator "pcbnew")
	(generator_version "9.0")
	(general
		(thickness 1.6)
		(legacy_teardrops no)
	)
	(paper "A4")
	(title_block
		(title "environment-sensor")
		(comment 1 "footprints 63-66 of 109")
	)
	(layers
		(0 "F.Cu" signal)
		(4 "In1.Cu" signal)
		(6 "In2.Cu" signal)
		(2 "B.Cu" signal)
		(9 "F.Adhes" user "F.Adhesive")
		(11 "B.Adhes" user "B.Adhesive")
		(13 "F.Paste" user)
		(15 "B.Paste" user)
		(5 "F.SilkS" user "F.Silkscreen")
		(7 "B.SilkS" user "B.Silkscreen")
		(1 "F.Mask" user)
		(3 "B.Mask" user)
		(17 "Dwgs.User" user "User.Drawings")
		(19 "Cmts.User" user "User.Comments")
		(21 "Eco1.User" user "User.Eco1")
		(23 "Eco2.User" user "User.Eco2")
		(25 "Edge.Cuts" user)
		(27 "Margin" user)
		(31 "F.CrtYd" user "F.Courtyard")
		(29 "B.CrtYd" user "B.Courtyard")
		(35 "F.Fab" user)
		(33 "B.Fab" user)
	)
	(footprint "antmicro-footprints:R_0402_1005Metric"
		(layer "F.Cu")
		(at 185.854 117.597 180)
		(descr "Resistor SMD 0402")
		(tags "resistor SMD 0402")
		(property "Reference" "R26"
			(at -0.846 -0.503 180)
			(layer "F.SilkS")
			(effects
				(font
					(size 0.7 0.7)
					(thickness 0.15)
				)
				(justify left bottom)
			)
		)
		(property "Value" "R_1k_0402"
			(at 0 1.4 180)
			(layer "F.Fab")
			(effects
				(font
					(size 0.7 0.7)
					(thickness 0.15)
				)
				(justify left bottom)
			)
		)
		(property "Description" "SMD Chip Resistor, 1 kohm, ± 1%, 63 mW, 0402 [1005 Metric], Thick Film, General Purpose"
			(at 0 0 180)
			(layer "F.Fab")
			(hide yes)
			(effects
				(font
					(size 1.27 1.27)
					(thickness 0.15)
				)
			)
		)
		(property "Author" "Antmicro"
			(at 371.708 235.194 0)
			(layer "F.Fab")
			(hide yes)
			(effects
				(font
					(size 1 1)
					(thickness 0.15)
				)
			)
		)
		(property "License" "Apache-2.0"
			(at 371.708 235.194 0)
			(layer "F.Fab")
			(hide yes)
			(effects
				(font
					(size 1 1)
					(thickness 0.15)
				)
			)
		)
		(property "MPN" "CR0402-FX-1001GLF"
			(at 371.708 235.194 0)
			(layer "F.Fab")
			(hide yes)
			(effects
				(font
					(size 1 1)
					(thickness 0.15)
				)
			)
		)
		(property "Manufacturer" "Bourns"
			(at 371.708 235.194 0)
			(layer "F.Fab")
			(hide yes)
			(effects
				(font
					(size 1 1)
					(thickness 0.15)
				)
			)
		)
		(property "Public" "False"
			(at 371.708 235.194 0)
			(layer "F.Fab")
			(hide yes)
			(effects
				(font
					(size 1 1)
					(thickness 0.15)
				)
			)
		)
		(property "Tolerance" "1%"
			(at 371.708 235.194 0)
			(layer "F.Fab")
			(hide yes)
			(effects
				(font
					(size 1 1)
					(thickness 0.15)
				)
			)
		)
		(property "Val" "1k"
			(at 371.708 235.194 0)
			(layer "F.Fab")
			(hide yes)
			(effects
				(font
					(size 1 1)
					(thickness 0.15)
				)
			)
		)
		(sheetfile "environment-sensor.kicad_sch")
		(attr smd)
		(fp_rect
			(start -0.925 -0.47)
			(end 0.925 0.47)
			(stroke
				(width 0.05)
				(type default)
			)
			(fill no)
			(layer "F.CrtYd")
		)
		(fp_rect
			(start -0.5 -0.25)
			(end 0.5 0.25)
			(stroke
				(width 0.15)
				(type solid)
			)
			(fill no)
			(layer "F.Fab")
		)
		(pad "1" smd roundrect
			(at -0.48 0 180)
			(size 0.59 0.64)
			(layers "F.Cu" "F.Mask" "F.Paste")
			(roundrect_rratio 0.25)
			(net 15 "/FRAM_WP")
			(pintype "passive")
		)
		(pad "2" smd roundrect
			(at 0.48 0 180)
			(size 0.59 0.64)
			(layers "F.Cu" "F.Mask" "F.Paste")
			(roundrect_rratio 0.25)
			(net 2 "+3V3")
			(pintype "passive")
		)
	)
	(footprint "antmicro-footprints:SOT-723"
		(layer "F.Cu")
		(at 201.6 117.95 180)
		(property "Reference" "D8"
			(at 1.1 -0.05 90)
			(layer "F.SilkS")
			(effects
				(font
					(size 0.65 0.65)
					(thickness 0.15)
				)
			)
		)
		(property "Value" "TPD2E009_SOT-9X3"
			(at -0.025 2.975 0)
			(layer "F.Fab")
			(effects
				(font
					(size 1 1)
					(thickness 0.15)
				)
			)
		)
		(property "Description" "TVS diode array, 8 kV, SOT-723, 5.5 V, 0.9 pF"
			(at 0 0 180)
			(layer "F.Fab")
			(hide yes)
			(effects
				(font
					(size 1.27 1.27)
					(thickness 0.15)
				)
			)
		)
		(property "Author" "Antmicro"
			(at 403.2 235.9 0)
			(layer "F.Fab")
			(hide yes)
			(effects
				(font
					(size 1 1)
					(thickness 0.15)
				)
			)
		)
		(property "License" "Apache-2.0"
			(at 403.2 235.9 0)
			(layer "F.Fab")
			(hide yes)
			(effects
				(font
					(size 1 1)
					(thickness 0.15)
				)
			)
		)
		(property "MPN" "TPD2E009DRTR"
			(at 403.2 235.9 0)
			(layer "F.Fab")
			(hide yes)
			(effects
				(font
					(size 1 1)
					(thickness 0.15)
				)
			)
		)
		(property "Manufacturer" "Texas Instruments"
			(at 403.2 235.9 0)
			(layer "F.Fab")
			(hide yes)
			(effects
				(font
					(size 1 1)
					(thickness 0.15)
				)
			)
		)
		(sheetfile "environment-sensor.kicad_sch")
		(attr smd)
		(fp_line
			(start 0.43 0.63)
			(end -0.22 0.63)
			(stroke
				(width 0.15)
				(type solid)
			)
			(layer "F.SilkS")
		)
		(fp_line
			(start 0.43 0.23)
			(end 0.43 0.63)
			(stroke
				(width 0.15)
				(type solid)
			)
			(layer "F.SilkS")
		)
		(fp_line
			(start 0.43 -0.23)
			(end 0.43 -0.63)
			(stroke
				(width 0.15)
				(type solid)
			)
			(layer "F.SilkS")
		)
		(fp_line
			(start 0.43 -0.63)
			(end -0.2175 -0.63)
			(stroke
				(width 0.15)
				(type solid)
			)
			(layer "F.SilkS")
		)
		(fp_line
			(start -0.43 -0.1375)
			(end -0.43 0.1375)
			(stroke
				(width 0.15)
				(type solid)
			)
			(layer "F.SilkS")
		)
		(fp_rect
			(start -0.83 -0.83)
			(end 0.83 0.83)
			(stroke
				(width 0.05)
				(type solid)
			)
			(fill no)
			(layer "F.CrtYd")
		)
		(fp_line
			(start 0.424 0.524)
			(end -0.424 0.524)
			(stroke
				(width 0.15)
				(type solid)
			)
			(layer "F.Fab")
		)
		(fp_line
			(start 0.424 -0.528)
			(end 0.424 0.524)
			(stroke
				(width 0.15)
				(type solid)
			)
			(layer "F.Fab")
		)
		(fp_line
			(start -0.09 -0.53)
			(end -0.43 -0.19)
			(stroke
				(width 0.15)
				(type solid)
			)
			(layer "F.Fab")
		)
		(fp_rect
			(start 0.424 0.524)
			(end -0.43 -0.528)
			(stroke
				(width 0.15)
				(type solid)
			)
			(fill no)
			(layer "F.Fab")
		)
		(fp_text user "${REFERENCE}"
			(at 0 0 0)
			(layer "F.Fab")
			(effects
				(font
					(size 0.2 0.2)
					(thickness 0.025)
				)
			)
		)
		(pad "1" smd rect
			(at -0.501 -0.401 90)
			(size 0.3 0.4)
			(layers "F.Cu" "F.Mask" "F.Paste")
			(net 8 "I2C_1_SCL")
			(pinfunction "1")
			(pintype "passive")
		)
		(pad "2" smd rect
			(at -0.501 0.399 90)
			(size 0.3 0.4)
			(layers "F.Cu" "F.Mask" "F.Paste")
			(net 9 "I2C_1_SDA")
			(pinfunction "2")
			(pintype "passive")
		)
		(pad "3" smd rect
			(at 0.499 -0.001 90)
			(size 0.3 0.4)
			(layers "F.Cu" "F.Mask" "F.Paste")
			(net 1 "GND")
			(pinfunction "3")
			(pintype "passive")
		)
	)
	(footprint "antmicro-footprints:C_0402_1005Metric"
		(layer "F.Cu")
		(at 198.479 128.999 180)
		(descr "Capacitor SMD 0402")
		(tags "capacitor SMD 0402")
		(property "Reference" "C15"
			(at -0.921 -0.301 180)
			(layer "F.SilkS")
			(effects
				(font
					(size 0.7 0.7)
					(thickness 0.15)
				)
				(justify left bottom)
			)
		)
		(property "Value" "C_100n_0402"
			(at 0 1.4 180)
			(layer "F.Fab")
			(effects
				(font
					(size 0.7 0.7)
					(thickness 0.15)
				)
				(justify left bottom)
			)
		)
		(property "Description" "SMD Multilayer Ceramic Capacitor, 0.1 µF, 50 V, 0402 [1005 Metric], ± 10%, X5R, GRM Series"
			(at 0 0 180)
			(layer "F.Fab")
			(hide yes)
			(effects
				(font
					(size 1.27 1.27)
					(thickness 0.15)
				)
			)
		)
		(property "Author" "Antmicro"
			(at 396.958 257.998 0)
			(layer "F.Fab")
			(hide yes)
			(effects
				(font
					(size 1 1)
					(thickness 0.15)
				)
			)
		)
		(property "Dielectric" "X5R"
			(at 396.958 257.998 0)
			(layer "F.Fab")
			(hide yes)
			(effects
				(font
					(size 1 1)
					(thickness 0.15)
				)
			)
		)
		(property "License" "Apache-2.0"
			(at 396.958 257.998 0)
			(layer "F.Fab")
			(hide yes)
			(effects
				(font
					(size 1 1)
					(thickness 0.15)
				)
			)
		)
		(property "MPN" "GRM155R61H104KE14D"
			(at 396.958 257.998 0)
			(layer "F.Fab")
			(hide yes)
			(effects
				(font
					(size 1 1)
					(thickness 0.15)
				)
			)
		)
		(property "Manufacturer" "Murata"
			(at 396.958 257.998 0)
			(layer "F.Fab")
			(hide yes)
			(effects
				(font
					(size 1 1)
					(thickness 0.15)
				)
			)
		)
		(property "Public" "False"
			(at 396.958 257.998 0)
			(layer "F.Fab")
			(hide yes)
			(effects
				(font
					(size 1 1)
					(thickness 0.15)
				)
			)
		)
		(property "Val" "100n"
			(at 396.958 257.998 0)
			(layer "F.Fab")
			(hide yes)
			(effects
				(font
					(size 1 1)
					(thickness 0.15)
				)
			)
		)
		(property "Voltage" "50V"
			(at 396.958 257.998 0)
			(layer "F.Fab")
			(hide yes)
			(effects
				(font
					(size 1 1)
					(thickness 0.15)
				)
			)
		)
		(sheetfile "environment-sensor.kicad_sch")
		(attr smd)
		(fp_rect
			(start -0.925 -0.47)
			(end 0.925 0.47)
			(stroke
				(width 0.05)
				(type default)
			)
			(fill no)
			(layer "F.CrtYd")
		)
		(fp_line
			(start 0.504 0.248)
			(end -0.494 0.248)
			(stroke
				(width 0.15)
				(type solid)
			)
			(layer "F.Fab")
		)
		(fp_line
			(start 0.504 -0.25)
			(end 0.504 0.248)
			(stroke
				(width 0.15)
				(type solid)
			)
			(layer "F.Fab")
		)
		(fp_line
			(start -0.494 0.248)
			(end -0.494 -0.25)
			(stroke
				(width 0.15)
				(type solid)
			)
			(layer "F.Fab")
		)
		(fp_line
			(start -0.494 -0.25)
			(end 0.504 -0.25)
			(stroke
				(width 0.15)
				(type solid)
			)
			(layer "F.Fab")
		)
		(pad "1" smd roundrect
			(at -0.48 0 180)
			(size 0.59 0.64)
			(layers "F.Cu" "F.Mask" "F.Paste")
			(roundrect_rratio 0.25)
			(net 1 "GND")
			(pintype "passive")
		)
		(pad "2" smd roundrect
			(at 0.48 0 180)
			(size 0.59 0.64)
			(layers "F.Cu" "F.Mask" "F.Paste")
			(roundrect_rratio 0.25)
			(net 2 "+3V3")
			(pintype "passive")
		)
	)
	(footprint "antmicro-footprints:USB-C_Receptacle_GCT_USB4105-GF-A"
		(layer "F.Cu")
		(at 162.652 126.75 -90)
		(property "Reference" "J1"
			(at -1.05 -5.198 90)
			(layer "F.SilkS")
			(effects
				(font
					(size 0.7 0.7)
					(thickness 0.15)
				)
				(justify right bottom)
			)
		)
		(property "Value" "USB-C_GCT_USB4105-GF-A"
			(at 0 5 90)
			(layer "F.Fab")
			(effects
				(font
					(size 0.7 0.7)
					(thickness 0.15)
				)
				(justify right bottom)
			)
		)
		(property "Description" "USB-C (USB TYPE-C) USB 2.0 Receptacle Connector 24 (16+8 Dummy) Position Surface Mount, Right Angle"
			(at 0 0 270)
			(layer "F.Fab")
			(hide yes)
			(effects
				(font
					(size 1.27 1.27)
					(thickness 0.15)
				)
			)
		)
		(property "Author" "Antmicro"
			(at 35.902 289.402 0)
			(layer "F.Fab")
			(hide yes)
			(effects
				(font
					(size 1 1)
					(thickness 0.15)
				)
			)
		)
		(property "License" "Apache-2.0"
			(at 35.902 289.402 0)
			(layer "F.Fab")
			(hide yes)
			(effects
				(font
					(size 1 1)
					(thickness 0.15)
				)
			)
		)
		(property "MPN" "USB4105-GF-A"
			(at 35.902 289.402 0)
			(layer "F.Fab")
			(hide yes)
			(effects
				(font
					(size 1 1)
					(thickness 0.15)
				)
			)
		)
		(property "Manufacturer" "GCT"
			(at 35.902 289.402 0)
			(layer "F.Fab")
			(hide yes)
			(effects
				(font
					(size 1 1)
					(thickness 0.15)
				)
			)
		)
		(property "VSD_Class" "USB-C"
			(at 35.902 289.402 0)
			(layer "F.Fab")
			(hide yes)
			(effects
				(font
					(size 1 1)
					(thickness 0.15)
				)
			)
		)
		(sheetfile "environment-sensor.kicad_sch")
		(attr smd)
		(fp_line
			(start -4.79 3.854)
			(end 4.788 3.854)
			(stroke
				(width 0.15)
				(type solid)
			)
			(layer "F.SilkS")
		)
		(fp_line
			(start 4.788 3.854)
			(end 4.788 2.575)
			(stroke
				(width 0.15)
				(type solid)
			)
			(layer "F.SilkS")
		)
		(fp_line
			(start -4.79 2.575)
			(end -4.79 3.854)
			(stroke
				(width 0.15)
				(type solid)
			)
			(layer "F.SilkS")
		)
		(fp_line
			(start -4.79 -1.395)
			(end -4.79 -0.145)
			(stroke
				(width 0.15)
				(type solid)
			)
			(layer "F.SilkS")
		)
		(fp_line
			(start 4.788 -1.395)
			(end 4.788 -0.145)
			(stroke
				(width 0.15)
				(type solid)
			)
			(layer "F.SilkS")
		)
		(fp_circle
			(center -3.8 -4.27071)
			(end -3.75 -4.22071)
			(stroke
				(width 0.15)
				(type solid)
			)
			(fill yes)
			(layer "F.SilkS")
		)
		(fp_rect
			(start -5.1 -4.4)
			(end 5.1 3.9)
			(stroke
				(width 0.05)
				(type solid)
			)
			(fill no)
			(layer "F.CrtYd")
		)
		(fp_line
			(start -4.79 3.854)
			(end -4.79 -3.676)
			(stroke
				(width 0.15)
				(type solid)
			)
			(layer "F.Fab")
		)
		(fp_line
			(start -4.702 3.854)
			(end 4.788 3.854)
			(stroke
				(width 0.15)
				(type solid)
			)
			(layer "F.Fab")
		)
		(fp_line
			(start 4.788 3.854)
			(end -4.79 3.854)
			(stroke
				(width 0.15)
				(type solid)
			)
			(layer "F.Fab")
		)
		(fp_line
			(start -4.79 -3.676)
			(end 4.788 -3.676)
			(stroke
				(width 0.15)
				(type solid)
			)
			(layer "F.Fab")
		)
		(fp_line
			(start 4.788 -3.676)
			(end 4.788 3.854)
			(stroke
				(width 0.15)
				(type solid)
			)
			(layer "F.Fab")
		)
		(pad "" np_thru_hole circle
			(at -2.891 -2.426 270)
			(size 0.65 0.65)
			(drill 0.65)
			(layers "*.Cu" "*.Mask")
		)
		(pad "" np_thru_hole circle
			(at 2.89 -2.426 270)
			(size 0.65 0.65)
			(drill 0.65)
			(layers "*.Cu" "*.Mask")
		)
		(pad "A1" smd roundrect
			(at -3.202 -3.5 270)
			(size 0.6 1.15)
			(layers "F.Cu" "F.Mask" "F.Paste")
			(roundrect_rratio 0.25)
			(net 1 "GND")
			(pinfunction "GND")
			(pintype "power_in")
		)
		(pad "A4" smd roundrect
			(at -2.4 -3.5 270)
			(size 0.6 1.15)
			(layers "F.Cu" "F.Mask" "F.Paste")
			(roundrect_rratio 0.25)
			(net 27 "/VBUS")
			(pinfunction "VBUS")
			(pintype "passive")
		)
		(pad "A5" smd roundrect
			(at -1.25 -3.5 270)
			(size 0.3 1.15)
			(layers "F.Cu" "F.Mask" "F.Paste")
			(roundrect_rratio 0.25)
			(net 4 "/USB_CC1")
			(pinfunction "CC_{1}")
			(pintype "bidirectional")
		)
		(pad "A6" smd roundrect
			(at -0.25 -3.5 270)
			(size 0.3 1.15)
			(layers "F.Cu" "F.Mask" "F.Paste")
			(roundrect_rratio 0.25)
			(net 6 "/USB_D_P")
			(pinfunction "D_{A}+")
			(pintype "bidirectional")
		)
		(pad "A7" smd roundrect
			(at 0.248 -3.5 270)
			(size 0.3 1.15)
			(layers "F.Cu" "F.Mask" "F.Paste")
			(roundrect_rratio 0.25)
			(net 7 "/USB_D_N")
			(pinfunction "D_{A}-")
			(pintype "bidirectional")
		)
		(pad "A8" smd roundrect
			(at 1.249 -3.5 270)
			(size 0.3 1.15)
			(layers "F.Cu" "F.Mask" "F.Paste")
			(roundrect_rratio 0.25)
			(net 34 "unconnected-(J1-SBU_{1}-PadA8)")
			(pinfunction "SBU_{1}")
			(pintype "bidirectional+no_connect")
		)
		(pad "A9" smd roundrect
			(at 2.398 -3.5 270)
			(size 0.6 1.15)
			(layers "F.Cu" "F.Mask" "F.Paste")
			(roundrect_rratio 0.25)
			(net 27 "/VBUS")
			(pinfunction "VBUS")
			(pintype "passive")
		)
		(pad "A12" smd roundrect
			(at 3.2 -3.5 270)
			(size 0.6 1.15)
			(layers "F.Cu" "F.Mask" "F.Paste")
			(roundrect_rratio 0.25)
			(net 1 "GND")
			(pinfunction "GND")
			(pintype "passive")
		)
		(pad "B1" smd roundrect
			(at 3.2 -3.5 270)
			(size 0.6 1.15)
			(layers "F.Cu" "F.Mask" "F.Paste")
			(roundrect_rratio 0.25)
			(net 1 "GND")
			(pinfunction "GND")
			(pintype "passive")
		)
		(pad "B4" smd roundrect
			(at 2.398 -3.5 270)
			(size 0.6 1.15)
			(layers "F.Cu" "F.Mask" "F.Paste")
			(roundrect_rratio 0.25)
			(net 27 "/VBUS")
			(pinfunction "VBUS")
			(pintype "passive")
		)
		(pad "B5" smd roundrect
			(at 1.749 -3.5 270)
			(size 0.3 1.15)
			(layers "F.Cu" "F.Mask" "F.Paste")
			(roundrect_rratio 0.25)
			(net 5 "/USB_CC2")
			(pinfunction "CC_{2}")
			(pintype "bidirectional")
		)
		(pad "B6" smd roundrect
			(at 0.748 -3.5 270)
			(size 0.3 1.15)
			(layers "F.Cu" "F.Mask" "F.Paste")
			(roundrect_rratio 0.25)
			(net 6 "/USB_D_P")
			(pinfunction "D_{B}+")
			(pintype "bidirectional")
		)
		(pad "B7" smd roundrect
			(at -0.75 -3.5 270)
			(size 0.3 1.15)
			(layers "F.Cu" "F.Mask" "F.Paste")
			(roundrect_rratio 0.25)
			(net 7 "/USB_D_N")
			(pinfunction "D_{B}-")
			(pintype "bidirectional")
		)
		(pad "B8" smd roundrect
			(at -1.75 -3.5 270)
			(size 0.3 1.15)
			(layers "F.Cu" "F.Mask" "F.Paste")
			(roundrect_rratio 0.25)
			(net 35 "unconnected-(J1-SBU_{2}-PadB8)")
			(pinfunction "SBU_{2}")
			(pintype "bidirectional+no_connect")
		)
		(pad "B9" smd roundrect
			(at -2.4 -3.5 270)
			(size 0.6 1.15)
			(layers "F.Cu" "F.Mask" "F.Paste")
			(roundrect_rratio 0.25)
			(net 27 "/VBUS")
			(pinfunction "VBUS")
			(pintype "passive")
		)
		(pad "B12" smd roundrect
			(at -3.202 -3.5 270)
			(size 0.6 1.15)
			(layers "F.Cu" "F.Mask" "F.Paste")
			(roundrect_rratio 0.25)
			(net 1 "GND")
			(pinfunction "GND")
			(pintype "passive")
		)
		(pad "SH" thru_hole oval
			(at -4.321 -2.926 270)
			(size 1.05 2.1)
			(drill oval 0.6 1.7)
			(layers "*.Cu" "*.Mask")
			(remove_unused_layers no)
			(net 3 "GNDREF")
			(pinfunction "SH")
			(pintype "passive")
		)
		(pad "SH" thru_hole oval
			(at -4.321 1.255 270)
			(size 1 2)
			(drill oval 0.6 1.4)
			(layers "*.Cu" "*.Mask")
			(remove_unused_layers no)
			(net 3 "GNDREF")
			(pinfunction "SH")
			(pintype "passive")
		)
		(pad "SH" thru_hole oval
			(at 4.32 -2.926 270)
			(size 1.05 2.1)
			(drill oval 0.6 1.7)
			(layers "*.Cu" "*.Mask")
			(remove_unused_layers no)
			(net 3 "GNDREF")
			(pinfunction "SH")
			(pintype "passive")
		)
		(pad "SH" thru_hole oval
			(at 4.32 1.255 270)
			(size 1 2)
			(drill oval 0.6 1.4)
			(layers "*.Cu" "*.Mask")
			(remove_unused_layers no)
			(net 3 "GNDREF")
			(pinfunction "SH")
			(pintype "passive")
		)
	)
)
